# BASEBOARD_FAB2 (Tioga Pass) — schematic netlist excerpt (pin names and nets, part order shuffled) for the footprints in the layout excerpt that follows; sources: Cadence DE-HDL packaged netlist, KiCad conversion of Wiwynn_Tioga_Pass_MB.brd

S9A2  SWITCH_D37771002  IC  pkg SM  page 175
  PIN1  = GND
  PIN2  = GND
  PIN3  = FP_PWR_BTN_R_N
  PIN4  = FP_PWR_BTN_R_N

C5F2  CAP_A  47UF 4V 20% X5R  pkg 0603V  page 217 : A = PVDDQ_ABC ; B = GND

(kicad_pcb
	(version 20260206)
	(generator "pcbnew")
	(generator_version "10.0")
	(general
		(thickness 1.6)
		(legacy_teardrops no)
	)
	(paper "A4")
	(title_block
		(title "Wiwynn_Tioga_Pass_MB.brd")
		(comment 1 "Tioga Pass / footprints 688-689 of 4770")
	)
	(layers
		(0 "F.Cu" signal "TOP")
		(4 "In1.Cu" signal "L2GND")
		(6 "In2.Cu" signal "L3")
		(8 "In3.Cu" signal "L4GND")
		(10 "In4.Cu" signal "L5")
		(12 "In5.Cu" signal "L6GND")
		(14 "In6.Cu" signal "L7VCC")
		(16 "In7.Cu" signal "L8VCC")
		(18 "In8.Cu" signal "L9GND")
		(20 "In9.Cu" signal "L10")
		(22 "In10.Cu" signal "L11GND")
		(24 "In11.Cu" signal "L12")
		(26 "In12.Cu" signal "L13GND")
		(2 "B.Cu" signal "BOTTOM")
		(9 "F.Adhes" user "F.Adhesive")
		(11 "B.Adhes" user "B.Adhesive")
		(13 "F.Paste" user "Package Geometry/Pastemask Top")
		(15 "B.Paste" user "Package Geometry/Pastemask Bottom")
		(5 "F.SilkS" user "Ref Des/Silkscreen Top")
		(7 "B.SilkS" user "Ref Des/Silkscreen Bottom")
		(1 "F.Mask" user "Board Geometry/Soldermask Top")
		(3 "B.Mask" user "Board Geometry/Soldermask Bottom")
		(17 "Dwgs.User" user "User.Drawings")
		(19 "Cmts.User" user "User.Comments")
		(21 "Eco1.User" user "User.Eco1")
		(23 "Eco2.User" user "User.Eco2")
		(25 "Edge.Cuts" user "Board Geometry/Outline")
		(27 "Margin" user)
		(31 "F.CrtYd" user "Package Geometry/Place Bound Top")
		(29 "B.CrtYd" user "Package Geometry/Place Bound Bottom")
		(35 "F.Fab" user "Ref Des/Assembly Top")
		(33 "B.Fab" user "Ref Des/Assembly Bottom")
	)
	(footprint ""
		(layer "F.Cu")
		(at 487.554016 -146.508978 -90)
		(property "Reference" "S9A2"
			(at 1.282446 -2.299208 270)
			(unlocked yes)
			(layer "F.SilkS")
			(effects
				(font
					(size 1.778 2.032)
					(thickness 0.1524)
				)
				(justify left)
			)
		)
		(property "Value" ""
			(at 0 0 270)
			(layer "F.Fab")
			(effects
				(font
					(size 1.27 1.27)
				)
			)
		)
		(duplicate_pad_numbers_are_jumpers no)
		(fp_line
			(start 1.800098 5.3721)
			(end 3.022092 5.3721)
			(stroke
				(width 0.1524)
				(type default)
			)
			(layer "F.SilkS")
		)
		(fp_line
			(start -0.7112 0.978154)
			(end -0.7112 3.52044)
			(stroke
				(width 0.1524)
				(type default)
			)
			(layer "F.SilkS")
		)
		(fp_line
			(start 5.5372 0.973836)
			(end 5.5372 3.52044)
			(stroke
				(width 0.1524)
				(type default)
			)
			(layer "F.SilkS")
		)
		(fp_line
			(start 3.024632 -0.8763)
			(end 1.800098 -0.8763)
			(stroke
				(width 0.1524)
				(type default)
			)
			(layer "F.SilkS")
		)
		(fp_circle
			(center -1.972818 -0.651002)
			(end -1.972818 -0.778002)
			(stroke
				(width 0.254)
				(type default)
			)
			(fill no)
			(layer "F.SilkS")
		)
		(fp_rect
			(start -0.7112 5.3721)
			(end 5.5372 -0.8763)
			(stroke
				(width 0)
				(type default)
			)
			(fill no)
			(layer "F.CrtYd")
		)
		(fp_line
			(start -0.7112 5.3721)
			(end -0.7112 -0.8763)
			(stroke
				(width 0.1)
				(type default)
			)
			(layer "F.Fab")
		)
		(fp_line
			(start 5.5372 5.3721)
			(end -0.7112 5.3721)
			(stroke
				(width 0.1)
				(type default)
			)
			(layer "F.Fab")
		)
		(fp_line
			(start -0.7112 -0.8763)
			(end 5.5372 -0.8763)
			(stroke
				(width 0.1)
				(type default)
			)
			(layer "F.Fab")
		)
		(fp_line
			(start 5.5372 -0.8763)
			(end 5.5372 5.3721)
			(stroke
				(width 0.1)
				(type default)
			)
			(layer "F.Fab")
		)
		(fp_circle
			(center -1.972818 -0.651002)
			(end -1.972818 -0.778002)
			(stroke
				(width 0.254)
				(type default)
			)
			(fill no)
			(layer "F.Fab")
		)
		(fp_text user "4"
			(at 7.040372 6.11124 0)
			(unlocked yes)
			(layer "F.SilkS")
			(effects
				(font
					(size 0.7874 0.5842)
					(thickness 0.1524)
				)
				(justify left)
			)
		)
		(fp_text user "3"
			(at -0.055372 6.018276 0)
			(unlocked yes)
			(layer "F.SilkS")
			(effects
				(font
					(size 0.7874 0.5842)
					(thickness 0.1524)
				)
				(justify left)
			)
		)
		(fp_text user "2"
			(at 5.997448 -1.599184 0)
			(unlocked yes)
			(layer "F.SilkS")
			(effects
				(font
					(size 0.7874 0.5842)
					(thickness 0.1524)
				)
				(justify left)
			)
		)
		(fp_text user "3"
			(at -1.454404 3.553206 0)
			(unlocked yes)
			(layer "F.Fab")
			(effects
				(font
					(size 0.7874 0.5842)
					(thickness 0.1524)
				)
				(justify left)
			)
		)
		(fp_text user "4"
			(at -1.422908 1.380998 0)
			(unlocked yes)
			(layer "F.Fab")
			(effects
				(font
					(size 0.7874 0.5842)
					(thickness 0.1524)
				)
				(justify left)
			)
		)
		(fp_text user "2"
			(at 5.080508 -0.918972 0)
			(unlocked yes)
			(layer "F.Fab")
			(effects
				(font
					(size 0.7874 0.5842)
					(thickness 0.1524)
				)
				(justify left)
			)
		)
		(pad "1" smd rect
			(at 0 0 270)
			(size 2.921 1.27)
			(layers "F.Cu" "F.Mask" "F.Paste")
			(net "GND")
		)
		(pad "2" smd rect
			(at 4.826 0 270)
			(size 2.921 1.27)
			(layers "F.Cu" "F.Mask" "F.Paste")
			(net "GND")
		)
		(pad "3" smd rect
			(at 0 4.4958 270)
			(size 2.921 1.27)
			(layers "F.Cu" "F.Mask" "F.Paste")
			(net "FP_PWR_BTN_R_N")
		)
		(pad "4" smd rect
			(at 4.826 4.4958 270)
			(size 2.921 1.27)
			(layers "F.Cu" "F.Mask" "F.Paste")
			(net "FP_PWR_BTN_R_N")
		)
	)
	(footprint ""
		(layer "F.Cu")
		(at 261.747 -23.241 180)
		(property "Reference" "C5F2"
			(at 0 0 180)
			(layer "F.SilkS")
			(hide yes)
			(effects
				(font
					(size 1.27 1.27)
				)
			)
		)
		(property "Value" ""
			(at 0 0 180)
			(layer "F.Fab")
			(effects
				(font
					(size 1.27 1.27)
				)
			)
		)
		(duplicate_pad_numbers_are_jumpers no)
		(fp_rect
			(start -0.500126 1.598422)
			(end 0.500126 -0.201422)
			(stroke
				(width 0)
				(type default)
			)
			(fill no)
			(layer "F.CrtYd")
		)
		(fp_line
			(start 0.500126 1.598422)
			(end -0.500126 1.598422)
			(stroke
				(width 0.1)
				(type default)
			)
			(layer "F.Fab")
		)
		(fp_line
			(start 0.500126 -0.201422)
			(end 0.500126 1.598422)
			(stroke
				(width 0.1)
				(type default)
			)
			(layer "F.Fab")
		)
		(fp_line
			(start -0.500126 1.598422)
			(end -0.500126 -0.201422)
			(stroke
				(width 0.1)
				(type default)
			)
			(layer "F.Fab")
		)
		(fp_line
			(start -0.500126 -0.201422)
			(end 0.500126 -0.201422)
			(stroke
				(width 0.1)
				(type default)
			)
			(layer "F.Fab")
		)
		(pad "1" smd rect
			(at 0 0 90)
			(size 0.889 0.9906)
			(layers "F.Cu" "F.Mask" "F.Paste")
			(net "PVDDQ_ABC")
		)
		(pad "2" smd rect
			(at 0 1.397 90)
			(size 0.889 0.9906)
			(layers "F.Cu" "F.Mask" "F.Paste")
			(net "GND")
		)
		(zone
			(layer "F.Cu")
			(hatch none 0.5)
			(connect_pads
				(clearance 0)
			)
			(min_thickness 0.25)
			(keepout
				(tracks not_allowed)
				(vias allowed)
				(pads allowed)
				(copperpour not_allowed)
				(footprints allowed)
			)
			(placement
				(enabled no)
				(sheetname "")
			)
			(fill
				(thermal_gap 0.5)
				(thermal_bridge_width 0.5)
				(island_removal_mode 0)
			)
			(polygon
				(pts
					(xy 262.2423 -24.1935) (xy 261.2517 -24.1935) (xy 261.2517 -23.6855) (xy 262.2423 -23.6855)
				)
			)
		)
		(zone
			(layer "F.Cu")
			(hatch none 0.5)
			(connect_pads
				(clearance 0)
			)
			(min_thickness 0.25)
			(keepout
				(tracks allowed)
				(vias not_allowed)
				(pads allowed)
				(copperpour not_allowed)
				(footprints allowed)
			)
			(placement
				(enabled no)
				(sheetname "")
			)
			(fill
				(thermal_gap 0.5)
				(thermal_bridge_width 0.5)
				(island_removal_mode 0)
			)
			(polygon
				(pts
					(xy 262.2423 -24.1935) (xy 261.2517 -24.1935) (xy 261.2517 -23.6855) (xy 262.2423 -23.6855)
				)
			)
		)
	)
)
